(kicad_pcb
	(version 20260206)
	(generator "pcbnew")
	(generator_version "10.0")
	(general
		(thickness 1.6)
		(legacy_teardrops no)
	)
	(paper "A4")
	(title_block
		(title "fcb — 12433-1M.1206WZS1330.brd")
		(comment 1 "Open Vault / Knox (Wiwynn) / footprints 385-391 of 495")
	)
	(layers
		(0 "F.Cu" signal "TOP")
		(4 "In1.Cu" signal "L2GND")
		(6 "In2.Cu" signal "L3VCC")
		(2 "B.Cu" signal "BOTTOM")
		(9 "F.Adhes" user "F.Adhesive")
		(11 "B.Adhes" user "B.Adhesive")
		(13 "F.Paste" user "Package Geometry/Pastemask Top")
		(15 "B.Paste" user "Package Geometry/Pastemask Bottom")
		(5 "F.SilkS" user "Ref Des/Silkscreen Top")
		(7 "B.SilkS" user "Ref Des/Silkscreen Bottom")
		(1 "F.Mask" user "Board Geometry/Soldermask Top")
		(3 "B.Mask" user "Board Geometry/Soldermask Bottom")
		(17 "Dwgs.User" user "User.Drawings")
		(19 "Cmts.User" user "User.Comments")
		(21 "Eco1.User" user "User.Eco1")
		(23 "Eco2.User" user "User.Eco2")
		(25 "Edge.Cuts" user "Board Geometry/Outline")
		(27 "Margin" user)
		(31 "F.CrtYd" user "Package Geometry/Place Bound Top")
		(29 "B.CrtYd" user "Package Geometry/Place Bound Bottom")
		(35 "F.Fab" user "Ref Des/Assembly Top")
		(33 "B.Fab" user "Ref Des/Assembly Bottom")
	)
	(footprint ""
		(layer "F.Cu")
		(at 17.63649 -172.175424 180)
		(property "Reference" "U3"
			(at 0 0 180)
			(layer "F.SilkS")
			(hide yes)
			(effects
				(font
					(size 1.27 1.27)
				)
			)
		)
		(property "Value" "74LVC1G32GW-1GP"
			(at -2.3368 -8.6868 180)
			(unlocked yes)
			(layer "F.Fab")
			(hide yes)
			(effects
				(font
					(size 1.016 1.016)
					(thickness 0.1524)
				)
			)
		)
		(property "Device Type" "SC70-5H44"
			(at -2.3114 -10.414 180)
			(unlocked yes)
			(layer "F.Fab")
			(hide yes)
			(effects
				(font
					(size 1.016 1.016)
					(thickness 0.1524)
				)
			)
		)
		(duplicate_pad_numbers_are_jumpers no)
		(fp_line
			(start 1.3843 -1.8034)
			(end 1.3843 -1.1176)
			(stroke
				(width 0.3302)
				(type default)
			)
			(layer "F.SilkS")
		)
		(fp_line
			(start 1.27 1.7018)
			(end -1.27 1.7018)
			(stroke
				(width 0.1524)
				(type default)
			)
			(layer "F.SilkS")
		)
		(fp_line
			(start 1.27 -1.7018)
			(end 1.27 1.7018)
			(stroke
				(width 0.1524)
				(type default)
			)
			(layer "F.SilkS")
		)
		(fp_line
			(start 0.6604 -1.8034)
			(end 1.3843 -1.8034)
			(stroke
				(width 0.3302)
				(type default)
			)
			(layer "F.SilkS")
		)
		(fp_line
			(start -1.27 1.7018)
			(end -1.27 -1.7018)
			(stroke
				(width 0.1524)
				(type default)
			)
			(layer "F.SilkS")
		)
		(fp_line
			(start -1.27 -1.7018)
			(end 1.27 -1.7018)
			(stroke
				(width 0.1524)
				(type default)
			)
			(layer "F.SilkS")
		)
		(fp_rect
			(start -1.524 1.9558)
			(end 1.524 -1.9558)
			(stroke
				(width 0)
				(type default)
			)
			(fill no)
			(layer "F.CrtYd")
		)
		(fp_poly
			(pts
				(xy -1.524 -1.9558) (xy 1.524 -1.9558) (xy 1.524 1.9558) (xy -1.524 1.9558)
			)
			(stroke
				(width 0)
				(type default)
			)
			(fill no)
			(layer "F.Fab")
		)
		(pad "1" smd rect
			(at 0.65024 -0.8255 180)
			(size 0.4064 1.2192)
			(layers "F.Cu" "F.Mask" "F.Paste")
			(net "SEB_PEER_1A_1B_HB_OUT")
		)
		(pad "2" smd rect
			(at 0 -0.8255 180)
			(size 0.4064 1.2192)
			(layers "F.Cu" "F.Mask" "F.Paste")
			(net "SEB_PEER_2A_2B_HB_OUT")
		)
		(pad "3" smd rect
			(at -0.65024 -0.8255 180)
			(size 0.4064 1.2192)
			(layers "F.Cu" "F.Mask" "F.Paste")
			(net "GND")
		)
		(pad "4" smd rect
			(at -0.65024 0.8255 180)
			(size 0.4064 1.2192)
			(layers "F.Cu" "F.Mask" "F.Paste")
			(net "THERMHOT#_R")
		)
		(pad "5" smd rect
			(at 0.65024 0.8255 180)
			(size 0.4064 1.2192)
			(layers "F.Cu" "F.Mask" "F.Paste")
			(net "P3V3")
		)
	)
	(footprint ""
		(layer "F.Cu")
		(at 21.0058 -247.9802 90)
		(property "Reference" "U4"
			(at 0 0 90)
			(layer "F.SilkS")
			(hide yes)
			(effects
				(font
					(size 1.27 1.27)
				)
			)
		)
		(property "Value" "SY8201ABC-GP"
			(at -0.0254 -11.9634 90)
			(unlocked yes)
			(layer "F.Fab")
			(hide yes)
			(effects
				(font
					(size 1.016 1.016)
					(thickness 0.1524)
				)
			)
		)
		(property "Device Type" "SOT-6H56"
			(at -0.0254 -13.5636 90)
			(unlocked yes)
			(layer "F.Fab")
			(hide yes)
			(effects
				(font
					(size 1.016 1.016)
					(thickness 0.1524)
				)
			)
		)
		(duplicate_pad_numbers_are_jumpers no)
		(fp_line
			(start 1.7145 -0.5842)
			(end -1.9685 -0.5842)
			(stroke
				(width 0.1524)
				(type default)
			)
			(layer "F.SilkS")
		)
		(fp_line
			(start -1.9685 -0.5842)
			(end -1.9685 0.5842)
			(stroke
				(width 0.1524)
				(type default)
			)
			(layer "F.SilkS")
		)
		(fp_line
			(start -1.9685 -0.4064)
			(end -1.5621 0)
			(stroke
				(width 0.1524)
				(type default)
			)
			(layer "F.SilkS")
		)
		(fp_line
			(start -1.5621 0)
			(end -1.9685 0.4064)
			(stroke
				(width 0.1524)
				(type default)
			)
			(layer "F.SilkS")
		)
		(fp_line
			(start 1.7145 0.5842)
			(end 1.7145 -0.5842)
			(stroke
				(width 0.1524)
				(type default)
			)
			(layer "F.SilkS")
		)
		(fp_line
			(start -1.9685 0.5842)
			(end 1.7145 0.5842)
			(stroke
				(width 0.1524)
				(type default)
			)
			(layer "F.SilkS")
		)
		(fp_line
			(start -1.9685 0.5842)
			(end -1.9685 2.3622)
			(stroke
				(width 0.508)
				(type default)
			)
			(layer "F.SilkS")
		)
		(fp_poly
			(pts
				(xy -1.27 -0.635) (xy 1.27 -0.635) (xy 1.27 0.635) (xy -1.27 0.635)
			)
			(stroke
				(width 0)
				(type default)
			)
			(fill yes)
			(layer "F.SilkS")
		)
		(fp_rect
			(start -1.9685 2.3622)
			(end 1.9685 -2.3622)
			(stroke
				(width 0)
				(type default)
			)
			(fill no)
			(layer "F.CrtYd")
		)
		(fp_poly
			(pts
				(xy -1.9685 -2.3622) (xy 1.9685 -2.3622) (xy 1.9685 2.3622) (xy -1.9685 2.3622)
			)
			(stroke
				(width 0)
				(type default)
			)
			(fill no)
			(layer "F.Fab")
		)
		(pad "1" smd rect
			(at -0.9525 1.3462 90)
			(size 0.5842 1.016)
			(layers "F.Cu" "F.Mask" "F.Paste")
			(net "P3V3_BS_NET")
		)
		(pad "2" smd rect
			(at 0 1.3462 90)
			(size 0.5842 1.016)
			(layers "F.Cu" "F.Mask" "F.Paste")
			(net "GND")
		)
		(pad "3" smd rect
			(at 0.9525 1.3462 90)
			(size 0.5842 1.016)
			(layers "F.Cu" "F.Mask" "F.Paste")
			(net "P3V3_FB")
		)
		(pad "4" smd rect
			(at 0.9525 -1.3462 90)
			(size 0.5842 1.016)
			(layers "F.Cu" "F.Mask" "F.Paste")
			(net "P3V3_EN")
		)
		(pad "5" smd rect
			(at 0 -1.3462 90)
			(size 0.5842 1.016)
			(layers "F.Cu" "F.Mask" "F.Paste")
			(net "P3V3_IN")
		)
		(pad "6" smd rect
			(at -0.9525 -1.3462 90)
			(size 0.5842 1.016)
			(layers "F.Cu" "F.Mask" "F.Paste")
			(net "P3V3_LX")
		)
	)
	(footprint ""
		(layer "F.Cu")
		(at 29.1338 -153.289 90)
		(property "Reference" "C8"
			(at 0 0 90)
			(layer "F.SilkS")
			(hide yes)
			(effects
				(font
					(size 1.27 1.27)
				)
			)
		)
		(property "Value" "SC2200P50V2KX-2GP"
			(at 1.1811 -2.7051 90)
			(unlocked yes)
			(layer "F.Fab")
			(hide yes)
			(effects
				(font
					(size 1.016 1.016)
					(thickness 0.1524)
				)
			)
		)
		(property "Device Type" "C402H22"
			(at 1.1811 -4.2291 90)
			(unlocked yes)
			(layer "F.Fab")
			(hide yes)
			(effects
				(font
					(size 1.016 1.016)
					(thickness 0.1524)
				)
			)
		)
		(duplicate_pad_numbers_are_jumpers no)
		(fp_rect
			(start -0.4318 0.9525)
			(end 0.4318 -0.9525)
			(stroke
				(width 0)
				(type default)
			)
			(fill no)
			(layer "F.CrtYd")
		)
		(fp_rect
			(start -0.4318 0.9525)
			(end 0.4318 -0.9525)
			(stroke
				(width 0)
				(type default)
			)
			(fill no)
			(layer "F.Fab")
		)
		(pad "1" smd custom
			(at 0 -0.4445 90)
			(size 0.1524 0.1524)
			(layers "F.Cu" "F.Mask" "F.Paste")
			(net "NCT7904_D2+")
			(options
				(clearance outline)
				(anchor circle)
			)
			(primitives
				(gr_poly
					(pts
						(arc
							(start 0.3048 -0.2032)
							(mid 0.275042 -0.275042)
							(end 0.2032 -0.3048)
						)
						(arc
							(start -0.2032 -0.3048)
							(mid -0.275042 -0.275042)
							(end -0.3048 -0.2032)
						)
						(arc
							(start -0.3048 0.2032)
							(mid -0.275042 0.275042)
							(end -0.2032 0.3048)
						)
						(arc
							(start 0.2032 0.3048)
							(mid 0.275042 0.275042)
							(end 0.3048 0.2032)
						)
					)
					(width 0)
					(fill yes)
				)
			)
		)
		(pad "2" smd custom
			(at 0 0.4445 90)
			(size 0.1524 0.1524)
			(layers "F.Cu" "F.Mask" "F.Paste")
			(net "NCT7904_D2-")
			(options
				(clearance outline)
				(anchor circle)
			)
			(primitives
				(gr_poly
					(pts
						(arc
							(start 0.3048 -0.2032)
							(mid 0.275042 -0.275042)
							(end 0.2032 -0.3048)
						)
						(arc
							(start -0.2032 -0.3048)
							(mid -0.275042 -0.275042)
							(end -0.3048 -0.2032)
						)
						(arc
							(start -0.3048 0.2032)
							(mid -0.275042 0.275042)
							(end -0.2032 0.3048)
						)
						(arc
							(start 0.2032 0.3048)
							(mid 0.275042 0.275042)
							(end 0.3048 0.2032)
						)
					)
					(width 0)
					(fill yes)
				)
			)
		)
	)
	(footprint ""
		(layer "F.Cu")
		(at 18.7198 -137.5664 180)
		(property "Reference" "PR104"
			(at 0 0 180)
			(layer "F.SilkS")
			(hide yes)
			(effects
				(font
					(size 1.27 1.27)
				)
			)
		)
		(property "Value" "2K7R2F-GP"
			(at 0.064008 -3.993896 180)
			(unlocked yes)
			(layer "F.Fab")
			(hide yes)
			(effects
				(font
					(size 1.016 1.016)
					(thickness 0.1524)
				)
			)
		)
		(property "Device Type" "R402H16"
			(at 0.064008 -5.517896 180)
			(unlocked yes)
			(layer "F.Fab")
			(hide yes)
			(effects
				(font
					(size 1.016 1.016)
					(thickness 0.1524)
				)
			)
		)
		(duplicate_pad_numbers_are_jumpers no)
		(fp_line
			(start 0.508 -0.9398)
			(end -0.508 -0.9398)
			(stroke
				(width 0.1524)
				(type default)
			)
			(layer "F.SilkS")
		)
		(fp_line
			(start -0.508 -0.9398)
			(end -0.508 0.9398)
			(stroke
				(width 0.1524)
				(type default)
			)
			(layer "F.SilkS")
		)
		(fp_rect
			(start -0.508 0.9398)
			(end 0.508 -0.9398)
			(stroke
				(width 0)
				(type default)
			)
			(fill no)
			(layer "F.CrtYd")
		)
		(fp_rect
			(start -0.508 0.9398)
			(end 0.508 -0.9398)
			(stroke
				(width 0)
				(type default)
			)
			(fill no)
			(layer "F.Fab")
		)
		(pad "1" smd custom
			(at 0 -0.4445 180)
			(size 0.1397 0.1397)
			(layers "F.Cu" "F.Mask" "F.Paste")
			(net "P12VU")
			(options
				(clearance outline)
				(anchor circle)
			)
			(primitives
				(gr_poly
					(pts
						(arc
							(start -0.1778 -0.2794)
							(mid -0.249642 -0.249642)
							(end -0.2794 -0.1778)
						)
						(arc
							(start -0.2794 0.1778)
							(mid -0.249642 0.249642)
							(end -0.1778 0.2794)
						)
						(arc
							(start 0.1778 0.2794)
							(mid 0.249642 0.249642)
							(end 0.2794 0.1778)
						)
						(arc
							(start 0.2794 -0.1778)
							(mid 0.249642 -0.249642)
							(end 0.1778 -0.2794)
						)
					)
					(width 0)
					(fill yes)
				)
			)
		)
		(pad "2" smd custom
			(at 0 0.4445 180)
			(size 0.1397 0.1397)
			(layers "F.Cu" "F.Mask" "F.Paste")
			(net "P12VU_2490_PG")
			(options
				(clearance outline)
				(anchor circle)
			)
			(primitives
				(gr_poly
					(pts
						(arc
							(start -0.1778 -0.2794)
							(mid -0.249642 -0.249642)
							(end -0.2794 -0.1778)
						)
						(arc
							(start -0.2794 0.1778)
							(mid -0.249642 0.249642)
							(end -0.1778 0.2794)
						)
						(arc
							(start 0.1778 0.2794)
							(mid 0.249642 0.249642)
							(end 0.2794 0.1778)
						)
						(arc
							(start 0.2794 -0.1778)
							(mid 0.249642 -0.249642)
							(end 0.1778 -0.2794)
						)
					)
					(width 0)
					(fill yes)
				)
			)
		)
	)
	(footprint ""
		(layer "F.Cu")
		(at 11.0236 -227.1776 180)
		(property "Reference" "R33"
			(at 0 0 180)
			(layer "F.SilkS")
			(hide yes)
			(effects
				(font
					(size 1.27 1.27)
				)
			)
		)
		(property "Value" "33R2F-3-GP"
			(at 0.064008 -3.993896 180)
			(unlocked yes)
			(layer "F.Fab")
			(hide yes)
			(effects
				(font
					(size 1.016 1.016)
					(thickness 0.1524)
				)
			)
		)
		(property "Device Type" "R402H16"
			(at 0.064008 -5.517896 180)
			(unlocked yes)
			(layer "F.Fab")
			(hide yes)
			(effects
				(font
					(size 1.016 1.016)
					(thickness 0.1524)
				)
			)
		)
		(duplicate_pad_numbers_are_jumpers no)
		(fp_line
			(start 0.508 -0.9398)
			(end -0.508 -0.9398)
			(stroke
				(width 0.1524)
				(type default)
			)
			(layer "F.SilkS")
		)
		(fp_line
			(start -0.508 -0.9398)
			(end -0.508 0.9398)
			(stroke
				(width 0.1524)
				(type default)
			)
			(layer "F.SilkS")
		)
		(fp_rect
			(start -0.508 0.9398)
			(end 0.508 -0.9398)
			(stroke
				(width 0)
				(type default)
			)
			(fill no)
			(layer "F.CrtYd")
		)
		(fp_rect
			(start -0.508 0.9398)
			(end 0.508 -0.9398)
			(stroke
				(width 0)
				(type default)
			)
			(fill no)
			(layer "F.Fab")
		)
		(pad "1" smd custom
			(at 0 -0.4445 180)
			(size 0.1397 0.1397)
			(layers "F.Cu" "F.Mask" "F.Paste")
			(net "P3V3")
			(options
				(clearance outline)
				(anchor circle)
			)
			(primitives
				(gr_poly
					(pts
						(arc
							(start -0.1778 -0.2794)
							(mid -0.249642 -0.249642)
							(end -0.2794 -0.1778)
						)
						(arc
							(start -0.2794 0.1778)
							(mid -0.249642 0.249642)
							(end -0.1778 0.2794)
						)
						(arc
							(start 0.1778 0.2794)
							(mid 0.249642 0.249642)
							(end 0.2794 0.1778)
						)
						(arc
							(start 0.2794 -0.1778)
							(mid 0.249642 -0.249642)
							(end 0.1778 -0.2794)
						)
					)
					(width 0)
					(fill yes)
				)
			)
		)
		(pad "2" smd custom
			(at 0 0.4445 180)
			(size 0.1397 0.1397)
			(layers "F.Cu" "F.Mask" "F.Paste")
			(net "LED_DR_LED3_BLUE")
			(options
				(clearance outline)
				(anchor circle)
			)
			(primitives
				(gr_poly
					(pts
						(arc
							(start -0.1778 -0.2794)
							(mid -0.249642 -0.249642)
							(end -0.2794 -0.1778)
						)
						(arc
							(start -0.2794 0.1778)
							(mid -0.249642 0.249642)
							(end -0.1778 0.2794)
						)
						(arc
							(start 0.1778 0.2794)
							(mid 0.249642 0.249642)
							(end 0.2794 0.1778)
						)
						(arc
							(start 0.2794 -0.1778)
							(mid 0.249642 -0.249642)
							(end 0.1778 -0.2794)
						)
					)
					(width 0)
					(fill yes)
				)
			)
		)
	)
	(footprint ""
		(layer "F.Cu")
		(at 8.0772 -275.2344 90)
		(property "Reference" "R38"
			(at 0 0 90)
			(layer "F.SilkS")
			(hide yes)
			(effects
				(font
					(size 1.27 1.27)
				)
			)
		)
		(property "Value" "0R2J-2-GP"
			(at 0.064008 -3.993896 90)
			(unlocked yes)
			(layer "F.Fab")
			(hide yes)
			(effects
				(font
					(size 1.016 1.016)
					(thickness 0.1524)
				)
			)
		)
		(property "Device Type" "R402H16"
			(at 0.064008 -5.517896 90)
			(unlocked yes)
			(layer "F.Fab")
			(hide yes)
			(effects
				(font
					(size 1.016 1.016)
					(thickness 0.1524)
				)
			)
		)
		(duplicate_pad_numbers_are_jumpers no)
		(fp_line
			(start 0.508 -0.9398)
			(end -0.508 -0.9398)
			(stroke
				(width 0.1524)
				(type default)
			)
			(layer "F.SilkS")
		)
		(fp_line
			(start -0.508 -0.9398)
			(end -0.508 0.9398)
			(stroke
				(width 0.1524)
				(type default)
			)
			(layer "F.SilkS")
		)
		(fp_rect
			(start -0.508 0.9398)
			(end 0.508 -0.9398)
			(stroke
				(width 0)
				(type default)
			)
			(fill no)
			(layer "F.CrtYd")
		)
		(fp_rect
			(start -0.508 0.9398)
			(end 0.508 -0.9398)
			(stroke
				(width 0)
				(type default)
			)
			(fill no)
			(layer "F.Fab")
		)
		(pad "1" smd custom
			(at 0 -0.4445 90)
			(size 0.1397 0.1397)
			(layers "F.Cu" "F.Mask" "F.Paste")
			(net "LED_DR_LED2_K")
			(options
				(clearance outline)
				(anchor circle)
			)
			(primitives
				(gr_poly
					(pts
						(arc
							(start -0.1778 -0.2794)
							(mid -0.249642 -0.249642)
							(end -0.2794 -0.1778)
						)
						(arc
							(start -0.2794 0.1778)
							(mid -0.249642 0.249642)
							(end -0.1778 0.2794)
						)
						(arc
							(start 0.1778 0.2794)
							(mid 0.249642 0.249642)
							(end 0.2794 0.1778)
						)
						(arc
							(start 0.2794 -0.1778)
							(mid 0.249642 -0.249642)
							(end 0.1778 -0.2794)
						)
					)
					(width 0)
					(fill yes)
				)
			)
		)
		(pad "2" smd custom
			(at 0 0.4445 90)
			(size 0.1397 0.1397)
			(layers "F.Cu" "F.Mask" "F.Paste")
			(net "GND")
			(options
				(clearance outline)
				(anchor circle)
			)
			(primitives
				(gr_poly
					(pts
						(arc
							(start -0.1778 -0.2794)
							(mid -0.249642 -0.249642)
							(end -0.2794 -0.1778)
						)
						(arc
							(start -0.2794 0.1778)
							(mid -0.249642 0.249642)
							(end -0.1778 0.2794)
						)
						(arc
							(start 0.1778 0.2794)
							(mid 0.249642 0.249642)
							(end 0.2794 0.1778)
						)
						(arc
							(start 0.2794 -0.1778)
							(mid 0.249642 -0.249642)
							(end 0.1778 -0.2794)
						)
					)
					(width 0)
					(fill yes)
				)
			)
		)
	)
	(footprint ""
		(layer "F.Cu")
		(at 24.4094 -135.1788)
		(property "Reference" "PR94"
			(at 0 0 0)
			(layer "F.SilkS")
			(hide yes)
			(effects
				(font
					(size 1.27 1.27)
				)
			)
		)
		(property "Value" "0R2J-2-GP"
			(at 0.064008 -3.993896 0)
			(unlocked yes)
			(layer "F.Fab")
			(hide yes)
			(effects
				(font
					(size 1.016 1.016)
					(thickness 0.1524)
				)
			)
		)
		(property "Device Type" "R402H16"
			(at 0.064008 -5.517896 0)
			(unlocked yes)
			(layer "F.Fab")
			(hide yes)
			(effects
				(font
					(size 1.016 1.016)
					(thickness 0.1524)
				)
			)
		)
		(duplicate_pad_numbers_are_jumpers no)
		(fp_line
			(start -0.508 -0.9398)
			(end -0.508 0.9398)
			(stroke
				(width 0.1524)
				(type default)
			)
			(layer "F.SilkS")
		)
		(fp_line
			(start 0.508 -0.9398)
			(end -0.508 -0.9398)
			(stroke
				(width 0.1524)
				(type default)
			)
			(layer "F.SilkS")
		)
		(fp_rect
			(start -0.508 0.9398)
			(end 0.508 -0.9398)
			(stroke
				(width 0)
				(type default)
			)
			(fill no)
			(layer "F.CrtYd")
		)
		(fp_rect
			(start -0.508 0.9398)
			(end 0.508 -0.9398)
			(stroke
				(width 0)
				(type default)
			)
			(fill no)
			(layer "F.Fab")
		)
		(pad "1" smd custom
			(at 0 -0.4445)
			(size 0.1397 0.1397)
			(layers "F.Cu" "F.Mask" "F.Paste")
			(net "P12VU_2490_VCC")
			(options
				(clearance outline)
				(anchor circle)
			)
			(primitives
				(gr_poly
					(pts
						(arc
							(start -0.1778 -0.2794)
							(mid -0.249642 -0.249642)
							(end -0.2794 -0.1778)
						)
						(arc
							(start -0.2794 0.1778)
							(mid -0.249642 0.249642)
							(end -0.1778 0.2794)
						)
						(arc
							(start 0.1778 0.2794)
							(mid 0.249642 0.249642)
							(end 0.2794 0.1778)
						)
						(arc
							(start 0.2794 -0.1778)
							(mid 0.249642 -0.249642)
							(end 0.1778 -0.2794)
						)
					)
					(width 0)
					(fill yes)
				)
			)
		)
		(pad "2" smd custom
			(at 0 0.4445)
			(size 0.1397 0.1397)
			(layers "F.Cu" "F.Mask" "F.Paste")
			(net "P12V")
			(options
				(clearance outline)
				(anchor circle)
			)
			(primitives
				(gr_poly
					(pts
						(arc
							(start -0.1778 -0.2794)
							(mid -0.249642 -0.249642)
							(end -0.2794 -0.1778)
						)
						(arc
							(start -0.2794 0.1778)
							(mid -0.249642 0.249642)
							(end -0.1778 0.2794)
						)
						(arc
							(start 0.1778 0.2794)
							(mid 0.249642 0.249642)
							(end 0.2794 0.1778)
						)
						(arc
							(start 0.2794 -0.1778)
							(mid 0.249642 -0.249642)
							(end 0.1778 -0.2794)
						)
					)
					(width 0)
					(fill yes)
				)
			)
		)
	)
)
